# T6G (Grand Teton) — schematic netlist excerpt (pin names and nets, part order shuffled) for the footprints in the layout excerpt that follows; sources: Cadence DE-HDL packaged netlist, KiCad conversion of 04192023_DAF0TMB3IC0_F0TG_MB_C_brd_V02_OCP.brd

R690  Q_RES  33.2 1% CHIP  pkg 0201LF  page 333 : A = SMB_RT_CPU1_P1_ROM_R_SDA ; B = SMB_RT_CPU1_P1_ROM_SDA
R348  Q_RES  33.2 1% CHIP  pkg 0402LF  page 151 : A = SMB_SML1_PMBUS_HSC_SDA ; B = SMB_SML1_PMBUS_HSC_R1_SDA
R6282  Q_RES  1K 1% EMPTY  pkg 0402LF  page 179 : A = P3V3_AUX ; B = USB_HUB2_TI_SMBUSZ_MRP_PROG_FUNC2

(kicad_pcb
	(version 20260206)
	(generator "pcbnew")
	(generator_version "10.0")
	(general
		(thickness 1.6)
		(legacy_teardrops no)
	)
	(paper "A4")
	(title_block
		(title "04192023_DAF0TMB3IC0_F0TG_MB_C_brd_V02_OCP.brd")
		(comment 1 "Grand Teton / footprints 1406-1408 of 8354")
	)
	(layers
		(0 "F.Cu" signal "TOP")
		(4 "In1.Cu" signal "GND")
		(6 "In2.Cu" signal "IN1")
		(8 "In3.Cu" signal "GND1")
		(10 "In4.Cu" signal "IN2")
		(12 "In5.Cu" signal "GND2")
		(14 "In6.Cu" signal "IN3")
		(16 "In7.Cu" signal "GND3")
		(18 "In8.Cu" signal "VCC")
		(20 "In9.Cu" signal "VCC1")
		(22 "In10.Cu" signal "GND4")
		(24 "In11.Cu" signal "IN4")
		(26 "In12.Cu" signal "GND5")
		(28 "In13.Cu" signal "IN5")
		(30 "In14.Cu" signal "GND6")
		(32 "In15.Cu" signal "IN6")
		(34 "In16.Cu" signal "GND7")
		(2 "B.Cu" signal "BOTTOM")
		(9 "F.Adhes" user "F.Adhesive")
		(11 "B.Adhes" user "B.Adhesive")
		(13 "F.Paste" user "Package Geometry/Pastemask Top")
		(15 "B.Paste" user "Package Geometry/Pastemask Bottom")
		(5 "F.SilkS" user "Ref Des/Silkscreen Top")
		(7 "B.SilkS" user "Ref Des/Silkscreen Bottom")
		(1 "F.Mask" user "Board Geometry/Soldermask Top")
		(3 "B.Mask" user "Board Geometry/Soldermask Bottom")
		(17 "Dwgs.User" user "User.Drawings")
		(19 "Cmts.User" user "User.Comments")
		(21 "Eco1.User" user "User.Eco1")
		(23 "Eco2.User" user "User.Eco2")
		(25 "Edge.Cuts" user "Board Geometry/Outline")
		(27 "Margin" user)
		(31 "F.CrtYd" user "Package Geometry/Place Bound Top")
		(29 "B.CrtYd" user "Package Geometry/Place Bound Bottom")
		(35 "F.Fab" user "Ref Des/Assembly Top")
		(33 "B.Fab" user "Ref Des/Assembly Bottom")
	)
	(footprint ""
		(layer "F.Cu")
		(at 117.347238 -41.17975 -90)
		(property "Reference" "R6282"
			(at 0 0 270)
			(layer "F.SilkS")
			(hide yes)
			(effects
				(font
					(size 1.27 1.27)
				)
			)
		)
		(property "Value" ""
			(at 0 0 270)
			(layer "F.Fab")
			(effects
				(font
					(size 1.27 1.27)
				)
			)
		)
		(duplicate_pad_numbers_are_jumpers no)
		(fp_line
			(start -0.7874 0.4064)
			(end -0.7874 -0.4064)
			(stroke
				(width 0.1524)
				(type default)
			)
			(layer "F.SilkS")
		)
		(fp_line
			(start 0.7874 0.4064)
			(end -0.7874 0.4064)
			(stroke
				(width 0.1524)
				(type default)
			)
			(layer "F.SilkS")
		)
		(fp_line
			(start -0.7874 -0.4064)
			(end 0.7874 -0.4064)
			(stroke
				(width 0.1524)
				(type default)
			)
			(layer "F.SilkS")
		)
		(fp_line
			(start 0.7874 -0.4064)
			(end 0.7874 0.4064)
			(stroke
				(width 0.1524)
				(type default)
			)
			(layer "F.SilkS")
		)
		(fp_line
			(start -0.67945 0.3048)
			(end -0.67945 -0.305054)
			(stroke
				(width 0.1)
				(type default)
			)
			(layer "F.Fab")
		)
		(fp_line
			(start -0.12065 0.3048)
			(end -0.67945 0.3048)
			(stroke
				(width 0.1)
				(type default)
			)
			(layer "F.Fab")
		)
		(fp_line
			(start 0.120396 0.3048)
			(end 0.120396 0.2794)
			(stroke
				(width 0.1)
				(type default)
			)
			(layer "F.Fab")
		)
		(fp_line
			(start 0.67945 0.3048)
			(end 0.120396 0.3048)
			(stroke
				(width 0.1)
				(type default)
			)
			(layer "F.Fab")
		)
		(fp_line
			(start -0.12065 0.2794)
			(end -0.12065 0.3048)
			(stroke
				(width 0.1)
				(type default)
			)
			(layer "F.Fab")
		)
		(fp_line
			(start 0.120396 0.2794)
			(end -0.12065 0.2794)
			(stroke
				(width 0.1)
				(type default)
			)
			(layer "F.Fab")
		)
		(fp_line
			(start -0.12065 -0.2794)
			(end 0.12065 -0.2794)
			(stroke
				(width 0.1)
				(type default)
			)
			(layer "F.Fab")
		)
		(fp_line
			(start 0.12065 -0.2794)
			(end 0.12065 -0.3048)
			(stroke
				(width 0.1)
				(type default)
			)
			(layer "F.Fab")
		)
		(fp_line
			(start 0.12065 -0.3048)
			(end 0.67945 -0.3048)
			(stroke
				(width 0.1)
				(type default)
			)
			(layer "F.Fab")
		)
		(fp_line
			(start 0.67945 -0.3048)
			(end 0.67945 0.3048)
			(stroke
				(width 0.1)
				(type default)
			)
			(layer "F.Fab")
		)
		(fp_line
			(start -0.67945 -0.305054)
			(end -0.12065 -0.305054)
			(stroke
				(width 0.1)
				(type default)
			)
			(layer "F.Fab")
		)
		(fp_line
			(start -0.12065 -0.305054)
			(end -0.12065 -0.2794)
			(stroke
				(width 0.1)
				(type default)
			)
			(layer "F.Fab")
		)
		(pad "1" smd circle
			(at -0.40005 0 270)
			(size 0 0)
			(layers "F.Cu" "F.Mask" "F.Paste")
			(net "P3V3_AUX")
		)
		(pad "2" smd circle
			(at 0.40005 0 270)
			(size 0 0)
			(layers "F.Cu" "F.Mask" "F.Paste")
			(net "USB_HUB2_TI_SMBUSZ_MRP_PROG_FUNC2")
		)
	)
	(footprint ""
		(layer "F.Cu")
		(at 178.851814 -410.630624)
		(property "Reference" "R348"
			(at 0 0 0)
			(layer "F.SilkS")
			(hide yes)
			(effects
				(font
					(size 1.27 1.27)
				)
			)
		)
		(property "Value" ""
			(at 0 0 0)
			(layer "F.Fab")
			(effects
				(font
					(size 1.27 1.27)
				)
			)
		)
		(duplicate_pad_numbers_are_jumpers no)
		(fp_line
			(start -0.7874 -0.4064)
			(end 0.7874 -0.4064)
			(stroke
				(width 0.1524)
				(type default)
			)
			(layer "F.SilkS")
		)
		(fp_line
			(start -0.7874 0.4064)
			(end -0.7874 -0.4064)
			(stroke
				(width 0.1524)
				(type default)
			)
			(layer "F.SilkS")
		)
		(fp_line
			(start 0.7874 -0.4064)
			(end 0.7874 0.4064)
			(stroke
				(width 0.1524)
				(type default)
			)
			(layer "F.SilkS")
		)
		(fp_line
			(start 0.7874 0.4064)
			(end -0.7874 0.4064)
			(stroke
				(width 0.1524)
				(type default)
			)
			(layer "F.SilkS")
		)
		(fp_line
			(start -0.67945 -0.305054)
			(end -0.12065 -0.305054)
			(stroke
				(width 0.1)
				(type default)
			)
			(layer "F.Fab")
		)
		(fp_line
			(start -0.67945 0.3048)
			(end -0.67945 -0.305054)
			(stroke
				(width 0.1)
				(type default)
			)
			(layer "F.Fab")
		)
		(fp_line
			(start -0.12065 -0.305054)
			(end -0.12065 -0.2794)
			(stroke
				(width 0.1)
				(type default)
			)
			(layer "F.Fab")
		)
		(fp_line
			(start -0.12065 -0.2794)
			(end 0.12065 -0.2794)
			(stroke
				(width 0.1)
				(type default)
			)
			(layer "F.Fab")
		)
		(fp_line
			(start -0.12065 0.2794)
			(end -0.12065 0.3048)
			(stroke
				(width 0.1)
				(type default)
			)
			(layer "F.Fab")
		)
		(fp_line
			(start -0.12065 0.3048)
			(end -0.67945 0.3048)
			(stroke
				(width 0.1)
				(type default)
			)
			(layer "F.Fab")
		)
		(fp_line
			(start 0.120396 0.2794)
			(end -0.12065 0.2794)
			(stroke
				(width 0.1)
				(type default)
			)
			(layer "F.Fab")
		)
		(fp_line
			(start 0.120396 0.3048)
			(end 0.120396 0.2794)
			(stroke
				(width 0.1)
				(type default)
			)
			(layer "F.Fab")
		)
		(fp_line
			(start 0.12065 -0.3048)
			(end 0.67945 -0.3048)
			(stroke
				(width 0.1)
				(type default)
			)
			(layer "F.Fab")
		)
		(fp_line
			(start 0.12065 -0.2794)
			(end 0.12065 -0.3048)
			(stroke
				(width 0.1)
				(type default)
			)
			(layer "F.Fab")
		)
		(fp_line
			(start 0.67945 -0.3048)
			(end 0.67945 0.3048)
			(stroke
				(width 0.1)
				(type default)
			)
			(layer "F.Fab")
		)
		(fp_line
			(start 0.67945 0.3048)
			(end 0.120396 0.3048)
			(stroke
				(width 0.1)
				(type default)
			)
			(layer "F.Fab")
		)
		(pad "1" smd circle
			(at -0.40005 0)
			(size 0 0)
			(layers "F.Cu" "F.Mask" "F.Paste")
			(net "SMB_SML1_PMBUS_HSC_SDA")
		)
		(pad "2" smd circle
			(at 0.40005 0)
			(size 0 0)
			(layers "F.Cu" "F.Mask" "F.Paste")
			(net "SMB_SML1_PMBUS_HSC_R1_SDA")
		)
	)
	(footprint ""
		(layer "F.Cu")
		(at 108.3564 -397.03248 90)
		(property "Reference" "R690"
			(at 0 0 90)
			(layer "F.SilkS")
			(hide yes)
			(effects
				(font
					(size 1.27 1.27)
				)
			)
		)
		(property "Value" ""
			(at 0 0 90)
			(layer "F.Fab")
			(effects
				(font
					(size 1.27 1.27)
				)
			)
		)
		(duplicate_pad_numbers_are_jumpers no)
		(fp_line
			(start 0.32512 -0.175006)
			(end 0.32512 0.175006)
			(stroke
				(width 0.1)
				(type default)
			)
			(layer "F.Fab")
		)
		(fp_line
			(start -0.32512 -0.175006)
			(end 0.32512 -0.175006)
			(stroke
				(width 0.1)
				(type default)
			)
			(layer "F.Fab")
		)
		(fp_line
			(start 0.32512 0.175006)
			(end -0.32512 0.175006)
			(stroke
				(width 0.1)
				(type default)
			)
			(layer "F.Fab")
		)
		(fp_line
			(start -0.32512 0.175006)
			(end -0.32512 -0.175006)
			(stroke
				(width 0.1)
				(type default)
			)
			(layer "F.Fab")
		)
		(pad "1" smd rect
			(at -0.2667 0 90)
			(size 0.3048 0.381)
			(layers "F.Cu" "F.Mask" "F.Paste")
			(net "SMB_RT_CPU1_P1_ROM_R_SDA")
		)
		(pad "2" smd rect
			(at 0.2667 0 270)
			(size 0.3048 0.381)
			(layers "F.Cu" "F.Mask" "F.Paste")
			(net "SMB_RT_CPU1_P1_ROM_SDA")
		)
	)
)
